(kicad_pcb
	(version 20260206)
	(generator "pcbnew")
	(generator_version "10.0")
	(general
		(thickness 1.6)
		(legacy_teardrops no)
	)
	(paper "A4")
	(title_block
		(title "panther-plus-userver — 13130-1b_20150205.brd")
		(comment 1 "Honey Badger (Wiwynn) / footprints 647-654 of 1509")
	)
	(layers
		(0 "F.Cu" signal "TOP")
		(4 "In1.Cu" signal "L2")
		(6 "In2.Cu" signal "L3")
		(8 "In3.Cu" signal "L4")
		(10 "In4.Cu" signal "L5")
		(12 "In5.Cu" signal "L6")
		(14 "In6.Cu" signal "L7")
		(16 "In7.Cu" signal "L8")
		(18 "In8.Cu" signal "L9")
		(20 "In9.Cu" signal "L10")
		(22 "In10.Cu" signal "L11")
		(2 "B.Cu" signal "BOTTOM")
		(9 "F.Adhes" user "F.Adhesive")
		(11 "B.Adhes" user "B.Adhesive")
		(13 "F.Paste" user "Package Geometry/Pastemask Top")
		(15 "B.Paste" user "Package Geometry/Pastemask Bottom")
		(5 "F.SilkS" user "Ref Des/Silkscreen Top")
		(7 "B.SilkS" user "Ref Des/Silkscreen Bottom")
		(1 "F.Mask" user "Board Geometry/Soldermask Top")
		(3 "B.Mask" user "Board Geometry/Soldermask Bottom")
		(17 "Dwgs.User" user "User.Drawings")
		(19 "Cmts.User" user "User.Comments")
		(21 "Eco1.User" user "User.Eco1")
		(23 "Eco2.User" user "User.Eco2")
		(25 "Edge.Cuts" user "Board Geometry/Outline")
		(27 "Margin" user)
		(31 "F.CrtYd" user "Package Geometry/Place Bound Top")
		(29 "B.CrtYd" user "Package Geometry/Place Bound Bottom")
		(35 "F.Fab" user "Ref Des/Assembly Top")
		(33 "B.Fab" user "Ref Des/Assembly Bottom")
	)
	(footprint ""
		(layer "F.Cu")
		(at 12.954 -31.877)
		(property "Reference" "PR199"
			(at 0 0 0)
			(layer "F.SilkS")
			(hide yes)
			(effects
				(font
					(size 1.27 1.27)
				)
			)
		)
		(property "Value" "10KR2F-2-GP"
			(at 1.7907 -1.1176 0)
			(unlocked yes)
			(layer "F.Fab")
			(hide yes)
			(effects
				(font
					(size 1.016 1.016)
					(thickness 0.1524)
				)
			)
		)
		(property "Device Type" "R402H16"
			(at 1.7907 -2.6416 0)
			(unlocked yes)
			(layer "F.Fab")
			(hide yes)
			(effects
				(font
					(size 1.016 1.016)
					(thickness 0.1524)
				)
			)
		)
		(duplicate_pad_numbers_are_jumpers no)
		(fp_rect
			(start -0.381 0.8382)
			(end 0.381 -0.8382)
			(stroke
				(width 0)
				(type default)
			)
			(fill no)
			(layer "F.CrtYd")
		)
		(fp_rect
			(start -0.381 0.8382)
			(end 0.381 -0.8382)
			(stroke
				(width 0)
				(type default)
			)
			(fill no)
			(layer "F.Fab")
		)
		(pad "1" smd custom
			(at 0 -0.4318)
			(size 0.127 0.127)
			(layers "F.Cu" "F.Mask" "F.Paste")
			(net "P3V3_STBY_VFB")
			(options
				(clearance outline)
				(anchor circle)
			)
			(primitives
				(gr_poly
					(pts
						(arc
							(start -0.2032 -0.2794)
							(mid -0.239121 -0.264521)
							(end -0.254 -0.2286)
						)
						(arc
							(start -0.254 0.2286)
							(mid -0.239121 0.264521)
							(end -0.2032 0.2794)
						)
						(arc
							(start 0.2032 0.2794)
							(mid 0.239121 0.264521)
							(end 0.254 0.2286)
						)
						(arc
							(start 0.254 -0.2286)
							(mid 0.239121 -0.264521)
							(end 0.2032 -0.2794)
						)
					)
					(width 0)
					(fill yes)
				)
			)
		)
		(pad "2" smd custom
			(at 0 0.4318)
			(size 0.127 0.127)
			(layers "F.Cu" "F.Mask" "F.Paste")
			(net "AGND_P3V3_STBY")
			(options
				(clearance outline)
				(anchor circle)
			)
			(primitives
				(gr_poly
					(pts
						(arc
							(start -0.2032 -0.2794)
							(mid -0.239121 -0.264521)
							(end -0.254 -0.2286)
						)
						(arc
							(start -0.254 0.2286)
							(mid -0.239121 0.264521)
							(end -0.2032 0.2794)
						)
						(arc
							(start 0.2032 0.2794)
							(mid 0.239121 0.264521)
							(end 0.254 0.2286)
						)
						(arc
							(start 0.254 -0.2286)
							(mid 0.239121 -0.264521)
							(end 0.2032 -0.2794)
						)
					)
					(width 0)
					(fill yes)
				)
			)
		)
	)
	(footprint ""
		(layer "F.Cu")
		(at 47.5488 -35.5854 180)
		(property "Reference" "C116"
			(at 0 0 180)
			(layer "F.SilkS")
			(hide yes)
			(effects
				(font
					(size 1.27 1.27)
				)
			)
		)
		(property "Value" "SC10U6D3V3MX-GP"
			(at -0.0254 -2.0193 180)
			(unlocked yes)
			(layer "F.Fab")
			(hide yes)
			(effects
				(font
					(size 1.016 1.016)
					(thickness 0.1524)
				)
			)
		)
		(property "Device Type" "C603H38"
			(at -0.0254 -3.5433 180)
			(unlocked yes)
			(layer "F.Fab")
			(hide yes)
			(effects
				(font
					(size 1.016 1.016)
					(thickness 0.1524)
				)
			)
		)
		(duplicate_pad_numbers_are_jumpers no)
		(fp_line
			(start -0.4064 0)
			(end 0.4064 0)
			(stroke
				(width 0.2286)
				(type default)
			)
			(layer "F.SilkS")
		)
		(fp_rect
			(start -0.635 1.1811)
			(end 0.635 -1.1811)
			(stroke
				(width 0)
				(type default)
			)
			(fill no)
			(layer "F.CrtYd")
		)
		(fp_rect
			(start -0.635 1.1811)
			(end 0.635 -1.1811)
			(stroke
				(width 0)
				(type default)
			)
			(fill no)
			(layer "F.Fab")
		)
		(pad "1" smd custom
			(at 0 -0.6604 180)
			(size 0.19685 0.19685)
			(layers "F.Cu" "F.Mask" "F.Paste")
			(net "XDP_RTEST#")
			(options
				(clearance outline)
				(anchor circle)
			)
			(primitives
				(gr_poly
					(pts
						(arc
							(start 0.508 -0.2921)
							(mid 0.478242 -0.363942)
							(end 0.4064 -0.3937)
						)
						(arc
							(start -0.4064 -0.3937)
							(mid -0.478242 -0.363942)
							(end -0.508 -0.2921)
						)
						(arc
							(start -0.508 0.2921)
							(mid -0.478242 0.363942)
							(end -0.4064 0.3937)
						)
						(arc
							(start 0.4064 0.3937)
							(mid 0.478242 0.363942)
							(end 0.508 0.2921)
						)
					)
					(width 0)
					(fill yes)
				)
			)
		)
		(pad "2" smd custom
			(at 0 0.6604 180)
			(size 0.19685 0.19685)
			(layers "F.Cu" "F.Mask" "F.Paste")
			(net "GND")
			(options
				(clearance outline)
				(anchor circle)
			)
			(primitives
				(gr_poly
					(pts
						(arc
							(start 0.508 -0.2921)
							(mid 0.478242 -0.363942)
							(end 0.4064 -0.3937)
						)
						(arc
							(start -0.4064 -0.3937)
							(mid -0.478242 -0.363942)
							(end -0.508 -0.2921)
						)
						(arc
							(start -0.508 0.2921)
							(mid -0.478242 0.363942)
							(end -0.4064 0.3937)
						)
						(arc
							(start 0.4064 0.3937)
							(mid 0.478242 0.363942)
							(end 0.508 0.2921)
						)
					)
					(width 0)
					(fill yes)
				)
			)
		)
	)
	(footprint ""
		(layer "F.Cu")
		(at 132.715 -51.689)
		(property "Reference" "R13"
			(at 0 0 0)
			(layer "F.SilkS")
			(hide yes)
			(effects
				(font
					(size 1.27 1.27)
				)
			)
		)
		(property "Value" "1KR2F-3-GP"
			(at 1.7907 -1.1176 0)
			(unlocked yes)
			(layer "F.Fab")
			(hide yes)
			(effects
				(font
					(size 1.016 1.016)
					(thickness 0.1524)
				)
			)
		)
		(property "Device Type" "R402H16"
			(at 1.7907 -2.6416 0)
			(unlocked yes)
			(layer "F.Fab")
			(hide yes)
			(effects
				(font
					(size 1.016 1.016)
					(thickness 0.1524)
				)
			)
		)
		(duplicate_pad_numbers_are_jumpers no)
		(fp_rect
			(start -0.381 0.8382)
			(end 0.381 -0.8382)
			(stroke
				(width 0)
				(type default)
			)
			(fill no)
			(layer "F.CrtYd")
		)
		(fp_rect
			(start -0.381 0.8382)
			(end 0.381 -0.8382)
			(stroke
				(width 0)
				(type default)
			)
			(fill no)
			(layer "F.Fab")
		)
		(pad "1" smd custom
			(at 0 -0.4318)
			(size 0.127 0.127)
			(layers "F.Cu" "F.Mask" "F.Paste")
			(net "P1V0")
			(options
				(clearance outline)
				(anchor circle)
			)
			(primitives
				(gr_poly
					(pts
						(arc
							(start -0.2032 -0.2794)
							(mid -0.239121 -0.264521)
							(end -0.254 -0.2286)
						)
						(arc
							(start -0.254 0.2286)
							(mid -0.239121 0.264521)
							(end -0.2032 0.2794)
						)
						(arc
							(start 0.2032 0.2794)
							(mid 0.239121 0.264521)
							(end 0.254 0.2286)
						)
						(arc
							(start 0.254 -0.2286)
							(mid 0.239121 -0.264521)
							(end 0.2032 -0.2794)
						)
					)
					(width 0)
					(fill yes)
				)
			)
		)
		(pad "2" smd custom
			(at 0 0.4318)
			(size 0.127 0.127)
			(layers "F.Cu" "F.Mask" "F.Paste")
			(net "MEMORY_HOT_N_LV_B2")
			(options
				(clearance outline)
				(anchor circle)
			)
			(primitives
				(gr_poly
					(pts
						(arc
							(start -0.2032 -0.2794)
							(mid -0.239121 -0.264521)
							(end -0.254 -0.2286)
						)
						(arc
							(start -0.254 0.2286)
							(mid -0.239121 0.264521)
							(end -0.2032 0.2794)
						)
						(arc
							(start 0.2032 0.2794)
							(mid 0.239121 0.264521)
							(end 0.254 0.2286)
						)
						(arc
							(start 0.254 -0.2286)
							(mid 0.239121 -0.264521)
							(end 0.2032 -0.2794)
						)
					)
					(width 0)
					(fill yes)
				)
			)
		)
	)
	(footprint ""
		(layer "F.Cu")
		(at 6.7818 -52.5526 90)
		(property "Reference" "R9"
			(at 0 0 90)
			(layer "F.SilkS")
			(hide yes)
			(effects
				(font
					(size 1.27 1.27)
				)
			)
		)
		(property "Value" "4K7R2F-GP"
			(at 0.064008 -3.993896 90)
			(unlocked yes)
			(layer "F.Fab")
			(hide yes)
			(effects
				(font
					(size 1.016 1.016)
					(thickness 0.1524)
				)
			)
		)
		(property "Device Type" "R402H16"
			(at 0.064008 -5.517896 90)
			(unlocked yes)
			(layer "F.Fab")
			(hide yes)
			(effects
				(font
					(size 1.016 1.016)
					(thickness 0.1524)
				)
			)
		)
		(duplicate_pad_numbers_are_jumpers no)
		(fp_rect
			(start -0.381 0.8382)
			(end 0.381 -0.8382)
			(stroke
				(width 0)
				(type default)
			)
			(fill no)
			(layer "F.CrtYd")
		)
		(fp_rect
			(start -0.381 0.8382)
			(end 0.381 -0.8382)
			(stroke
				(width 0)
				(type default)
			)
			(fill no)
			(layer "F.Fab")
		)
		(pad "1" smd custom
			(at 0 -0.4318 90)
			(size 0.127 0.127)
			(layers "F.Cu" "F.Mask" "F.Paste")
			(net "P3V3_STBY")
			(options
				(clearance outline)
				(anchor circle)
			)
			(primitives
				(gr_poly
					(pts
						(arc
							(start -0.2032 -0.2794)
							(mid -0.239121 -0.264521)
							(end -0.254 -0.2286)
						)
						(arc
							(start -0.254 0.2286)
							(mid -0.239121 0.264521)
							(end -0.2032 0.2794)
						)
						(arc
							(start 0.2032 0.2794)
							(mid 0.239121 0.264521)
							(end 0.254 0.2286)
						)
						(arc
							(start 0.254 -0.2286)
							(mid 0.239121 -0.264521)
							(end 0.2032 -0.2794)
						)
					)
					(width 0)
					(fill yes)
				)
			)
		)
		(pad "2" smd custom
			(at 0 0.4318 90)
			(size 0.127 0.127)
			(layers "F.Cu" "F.Mask" "F.Paste")
			(net "TEMP_1_A1")
			(options
				(clearance outline)
				(anchor circle)
			)
			(primitives
				(gr_poly
					(pts
						(arc
							(start -0.2032 -0.2794)
							(mid -0.239121 -0.264521)
							(end -0.254 -0.2286)
						)
						(arc
							(start -0.254 0.2286)
							(mid -0.239121 0.264521)
							(end -0.2032 0.2794)
						)
						(arc
							(start 0.2032 0.2794)
							(mid 0.239121 0.264521)
							(end 0.254 0.2286)
						)
						(arc
							(start 0.254 -0.2286)
							(mid 0.239121 -0.264521)
							(end 0.2032 -0.2794)
						)
					)
					(width 0)
					(fill yes)
				)
			)
		)
	)
	(footprint ""
		(layer "F.Cu")
		(at 154.94 -12.447778 90)
		(property "Reference" "PR217"
			(at 0 0 90)
			(layer "F.SilkS")
			(hide yes)
			(effects
				(font
					(size 1.27 1.27)
				)
			)
		)
		(property "Value" "0R2J-2-GP"
			(at 1.7907 -1.1176 90)
			(unlocked yes)
			(layer "F.Fab")
			(hide yes)
			(effects
				(font
					(size 1.016 1.016)
					(thickness 0.1524)
				)
			)
		)
		(property "Device Type" "R402H16"
			(at 1.7907 -2.6416 90)
			(unlocked yes)
			(layer "F.Fab")
			(hide yes)
			(effects
				(font
					(size 1.016 1.016)
					(thickness 0.1524)
				)
			)
		)
		(duplicate_pad_numbers_are_jumpers no)
		(fp_rect
			(start -0.381 0.8382)
			(end 0.381 -0.8382)
			(stroke
				(width 0)
				(type default)
			)
			(fill no)
			(layer "F.CrtYd")
		)
		(fp_rect
			(start -0.381 0.8382)
			(end 0.381 -0.8382)
			(stroke
				(width 0)
				(type default)
			)
			(fill no)
			(layer "F.Fab")
		)
		(pad "1" smd custom
			(at 0 -0.4318 90)
			(size 0.127 0.127)
			(layers "F.Cu" "F.Mask" "F.Paste")
			(net "VR_PVDDR_A_VTT")
			(options
				(clearance outline)
				(anchor circle)
			)
			(primitives
				(gr_poly
					(pts
						(arc
							(start -0.2032 -0.2794)
							(mid -0.239121 -0.264521)
							(end -0.254 -0.2286)
						)
						(arc
							(start -0.254 0.2286)
							(mid -0.239121 0.264521)
							(end -0.2032 0.2794)
						)
						(arc
							(start 0.2032 0.2794)
							(mid 0.239121 0.264521)
							(end 0.254 0.2286)
						)
						(arc
							(start 0.254 -0.2286)
							(mid 0.239121 -0.264521)
							(end 0.2032 -0.2794)
						)
					)
					(width 0)
					(fill yes)
				)
			)
		)
		(pad "2" smd custom
			(at 0 0.4318 90)
			(size 0.127 0.127)
			(layers "F.Cu" "F.Mask" "F.Paste")
			(net "PV_VDDR")
			(options
				(clearance outline)
				(anchor circle)
			)
			(primitives
				(gr_poly
					(pts
						(arc
							(start -0.2032 -0.2794)
							(mid -0.239121 -0.264521)
							(end -0.254 -0.2286)
						)
						(arc
							(start -0.254 0.2286)
							(mid -0.239121 0.264521)
							(end -0.2032 0.2794)
						)
						(arc
							(start 0.2032 0.2794)
							(mid 0.239121 0.264521)
							(end 0.254 0.2286)
						)
						(arc
							(start 0.254 -0.2286)
							(mid 0.239121 -0.264521)
							(end 0.2032 -0.2794)
						)
					)
					(width 0)
					(fill yes)
				)
			)
		)
	)
	(footprint ""
		(layer "F.Cu")
		(at 156.464 -27.305)
		(property "Reference" "C236"
			(at 0 0 0)
			(layer "F.SilkS")
			(hide yes)
			(effects
				(font
					(size 1.27 1.27)
				)
			)
		)
		(property "Value" "SCD1U10V2KX-5GP"
			(at 1.1811 -2.7051 0)
			(unlocked yes)
			(layer "F.Fab")
			(hide yes)
			(effects
				(font
					(size 1.016 1.016)
					(thickness 0.1524)
				)
			)
		)
		(property "Device Type" "C402H22"
			(at 1.1811 -4.2291 0)
			(unlocked yes)
			(layer "F.Fab")
			(hide yes)
			(effects
				(font
					(size 1.016 1.016)
					(thickness 0.1524)
				)
			)
		)
		(duplicate_pad_numbers_are_jumpers no)
		(fp_rect
			(start -0.381 0.7366)
			(end 0.381 -0.7366)
			(stroke
				(width 0)
				(type default)
			)
			(fill no)
			(layer "F.CrtYd")
		)
		(fp_rect
			(start -0.381 0.7366)
			(end 0.381 -0.7366)
			(stroke
				(width 0)
				(type default)
			)
			(fill no)
			(layer "F.Fab")
		)
		(pad "1" smd custom
			(at 0 -0.4572)
			(size 0.1143 0.1143)
			(layers "F.Cu" "F.Mask" "F.Paste")
			(net "P3V3_STBY")
			(options
				(clearance outline)
				(anchor circle)
			)
			(primitives
				(gr_poly
					(pts
						(arc
							(start -0.254 -0.1778)
							(mid -0.239121 -0.213721)
							(end -0.2032 -0.2286)
						)
						(arc
							(start 0.2032 -0.2286)
							(mid 0.239121 -0.213721)
							(end 0.254 -0.1778)
						)
						(arc
							(start 0.254 0.1778)
							(mid 0.239121 0.213721)
							(end 0.2032 0.2286)
						)
						(arc
							(start -0.2032 0.2286)
							(mid -0.239121 0.213721)
							(end -0.254 0.1778)
						)
					)
					(width 0)
					(fill yes)
				)
			)
		)
		(pad "2" smd custom
			(at 0 0.4572)
			(size 0.1143 0.1143)
			(layers "F.Cu" "F.Mask" "F.Paste")
			(net "GND")
			(options
				(clearance outline)
				(anchor circle)
			)
			(primitives
				(gr_poly
					(pts
						(arc
							(start -0.254 -0.1778)
							(mid -0.239121 -0.213721)
							(end -0.2032 -0.2286)
						)
						(arc
							(start 0.2032 -0.2286)
							(mid 0.239121 -0.213721)
							(end 0.254 -0.1778)
						)
						(arc
							(start 0.254 0.1778)
							(mid 0.239121 0.213721)
							(end 0.2032 0.2286)
						)
						(arc
							(start -0.2032 0.2286)
							(mid -0.239121 0.213721)
							(end -0.254 0.1778)
						)
					)
					(width 0)
					(fill yes)
				)
			)
		)
	)
	(footprint ""
		(layer "F.Cu")
		(at 60.706 -25.527)
		(property "Reference" "R254"
			(at 0 0 0)
			(layer "F.SilkS")
			(hide yes)
			(effects
				(font
					(size 1.27 1.27)
				)
			)
		)
		(property "Value" "4K02R2F-GP"
			(at 0.064008 -3.993896 0)
			(unlocked yes)
			(layer "F.Fab")
			(hide yes)
			(effects
				(font
					(size 1.016 1.016)
					(thickness 0.1524)
				)
			)
		)
		(property "Device Type" "R402H16"
			(at 0.064008 -5.517896 0)
			(unlocked yes)
			(layer "F.Fab")
			(hide yes)
			(effects
				(font
					(size 1.016 1.016)
					(thickness 0.1524)
				)
			)
		)
		(duplicate_pad_numbers_are_jumpers no)
		(fp_rect
			(start -0.381 0.8382)
			(end 0.381 -0.8382)
			(stroke
				(width 0)
				(type default)
			)
			(fill no)
			(layer "F.CrtYd")
		)
		(fp_rect
			(start -0.381 0.8382)
			(end 0.381 -0.8382)
			(stroke
				(width 0)
				(type default)
			)
			(fill no)
			(layer "F.Fab")
		)
		(pad "1" smd custom
			(at 0 -0.4318)
			(size 0.127 0.127)
			(layers "F.Cu" "F.Mask" "F.Paste")
			(net "SW_P1V8_EN_G")
			(options
				(clearance outline)
				(anchor circle)
			)
			(primitives
				(gr_poly
					(pts
						(arc
							(start -0.2032 -0.2794)
							(mid -0.239121 -0.264521)
							(end -0.254 -0.2286)
						)
						(arc
							(start -0.254 0.2286)
							(mid -0.239121 0.264521)
							(end -0.2032 0.2794)
						)
						(arc
							(start 0.2032 0.2794)
							(mid 0.239121 0.264521)
							(end 0.254 0.2286)
						)
						(arc
							(start 0.254 -0.2286)
							(mid 0.239121 -0.264521)
							(end 0.2032 -0.2794)
						)
					)
					(width 0)
					(fill yes)
				)
			)
		)
		(pad "2" smd custom
			(at 0 0.4318)
			(size 0.127 0.127)
			(layers "F.Cu" "F.Mask" "F.Paste")
			(net "P3V3_STBY")
			(options
				(clearance outline)
				(anchor circle)
			)
			(primitives
				(gr_poly
					(pts
						(arc
							(start -0.2032 -0.2794)
							(mid -0.239121 -0.264521)
							(end -0.254 -0.2286)
						)
						(arc
							(start -0.254 0.2286)
							(mid -0.239121 0.264521)
							(end -0.2032 0.2794)
						)
						(arc
							(start 0.2032 0.2794)
							(mid 0.239121 0.264521)
							(end 0.254 0.2286)
						)
						(arc
							(start 0.254 -0.2286)
							(mid 0.239121 -0.264521)
							(end 0.2032 -0.2794)
						)
					)
					(width 0)
					(fill yes)
				)
			)
		)
	)
	(footprint ""
		(layer "F.Cu")
		(at 29.3243 -35.433)
		(property "Reference" "R489"
			(at 0 0 0)
			(layer "F.SilkS")
			(hide yes)
			(effects
				(font
					(size 1.27 1.27)
				)
			)
		)
		(property "Value" "51R2F-2-GP"
			(at 1.7907 -1.1176 0)
			(unlocked yes)
			(layer "F.Fab")
			(hide yes)
			(effects
				(font
					(size 1.016 1.016)
					(thickness 0.1524)
				)
			)
		)
		(property "Device Type" "R402H16"
			(at 1.7907 -2.6416 0)
			(unlocked yes)
			(layer "F.Fab")
			(hide yes)
			(effects
				(font
					(size 1.016 1.016)
					(thickness 0.1524)
				)
			)
		)
		(duplicate_pad_numbers_are_jumpers no)
		(fp_rect
			(start -0.381 0.8382)
			(end 0.381 -0.8382)
			(stroke
				(width 0)
				(type default)
			)
			(fill no)
			(layer "F.CrtYd")
		)
		(fp_rect
			(start -0.381 0.8382)
			(end 0.381 -0.8382)
			(stroke
				(width 0)
				(type default)
			)
			(fill no)
			(layer "F.Fab")
		)
		(pad "1" smd custom
			(at 0 -0.4318)
			(size 0.127 0.127)
			(layers "F.Cu" "F.Mask" "F.Paste")
			(net "XDP_SOC_CPU_TDI")
			(options
				(clearance outline)
				(anchor circle)
			)
			(primitives
				(gr_poly
					(pts
						(arc
							(start -0.2032 -0.2794)
							(mid -0.239121 -0.264521)
							(end -0.254 -0.2286)
						)
						(arc
							(start -0.254 0.2286)
							(mid -0.239121 0.264521)
							(end -0.2032 0.2794)
						)
						(arc
							(start 0.2032 0.2794)
							(mid 0.239121 0.264521)
							(end 0.254 0.2286)
						)
						(arc
							(start 0.254 -0.2286)
							(mid 0.239121 -0.264521)
							(end 0.2032 -0.2794)
						)
					)
					(width 0)
					(fill yes)
				)
			)
		)
		(pad "2" smd custom
			(at 0 0.4318)
			(size 0.127 0.127)
			(layers "F.Cu" "F.Mask" "F.Paste")
			(net "GND")
			(options
				(clearance outline)
				(anchor circle)
			)
			(primitives
				(gr_poly
					(pts
						(arc
							(start -0.2032 -0.2794)
							(mid -0.239121 -0.264521)
							(end -0.254 -0.2286)
						)
						(arc
							(start -0.254 0.2286)
							(mid -0.239121 0.264521)
							(end -0.2032 0.2794)
						)
						(arc
							(start 0.2032 0.2794)
							(mid 0.239121 0.264521)
							(end 0.254 0.2286)
						)
						(arc
							(start 0.254 -0.2286)
							(mid 0.239121 -0.264521)
							(end 0.2032 -0.2794)
						)
					)
					(width 0)
					(fill yes)
				)
			)
		)
	)
)
